# BASEBOARD_FAB2 (Tioga Pass) — schematic netlist excerpt (pin names and nets, part order shuffled) for the footprints in the layout excerpt that follows; sources: Cadence DE-HDL packaged netlist, KiCad conversion of Wiwynn_Tioga_Pass_MB.brd

J1A1  SCONN288_H44441004  SCONN  pkg PIP  page 87
  \12v\(1)  = P12V_NVDIMM_KLM
  VSS(93)  = GND
  DQ(4)  = M_M_DQ<5>
  VSS(92)  = GND
  DQ(0)  = M_M_DQ<1>
  VSS(91)  = GND
  DQS9P  = M_M_DQS_DP<9>
  DQS9N  = M_M_DQS_DN<9>
  VSS(90)  = GND
  DQ(6)  = M_M_DQ<7>
  VSS(89)  = GND
  DQ(2)  = M_M_DQ<3>
  VSS(88)  = GND
  DQ(12)  = M_M_DQ<13>
  VSS(87)  = GND
  DQ(8)  = M_M_DQ<9>
  VSS(86)  = GND
  DQS10P  = M_M_DQS_DP<10>
  DQS10N  = M_M_DQS_DN<10>
  VSS(85)  = GND
  DQ(14)  = M_M_DQ<15>
  VSS(84)  = GND
  DQ(10)  = M_M_DQ<11>
  VSS(83)  = GND
  DQ(20)  = M_M_DQ<21>
  VSS(82)  = GND
  DQ(16)  = M_M_DQ<17>
  VSS(81)  = GND
  DQS11P  = M_M_DQS_DP<11>
  DQS11N  = M_M_DQS_DN<11>
  VSS(80)  = GND
  DQ(22)  = M_M_DQ<23>
  VSS(79)  = GND
  DQ(18)  = M_M_DQ<19>
  VSS(78)  = GND
  DQ(28)  = M_M_DQ<29>
  VSS(77)  = GND
  DQ(24)  = M_M_DQ<25>
  VSS(76)  = GND
  DQS12P  = M_M_DQS_DP<12>
  DQS12N  = M_M_DQS_DN<12>
  VSS(75)  = GND
  DQ(30)  = M_M_DQ<31>
  VSS(74)  = GND
  DQ(26)  = M_M_DQ<27>
  VSS(73)  = GND
  CB(4)  = M_M_ECC<5>
  VSS(72)  = GND
  CB(0)  = M_M_ECC<1>
  VSS(71)  = GND
  DQS17P  = M_M_DQS_DP<17>
  DQS17N  = M_M_DQS_DN<17>
  VSS(70)  = GND
  CB(6)  = M_M_ECC<7>
  VSS(69)  = GND
  CB(2)  = M_M_ECC<3>
  VSS(68)  = GND
  RESET_N  = M_KLM_RST_N
  VDD(25)  = PVDDQ_KLM
  CKE(0)  = M_M_CKE<0>
  VDD(24)  = PVDDQ_KLM
  ACT_N  = M_M_ACT_N
  BG(0)  = M_M_BG<0>
  VDD(23)  = PVDDQ_KLM
  A12  = M_M_MA<12>
  A9  = M_M_MA<9>
  VDD(22)  = PVDDQ_KLM
  A8  = M_M_MA<8>
  A6  = M_M_MA<6>
  VDD(21)  = PVDDQ_KLM
  A3  = M_M_MA<3>
  A1  = M_M_MA<1>
  VDD(20)  = PVDDQ_KLM
  CK0P  = M_M_CLK_DP<0>
  CK0N  = M_M_CLK_DN<0>
  VDD(19)  = PVDDQ_KLM
  VTT(1)  = PVTT_KLM
  EVENT_N  = FM_DIMM_EVENT_COD_N
  A0  = M_M_MA<0>
  VDD(18)  = PVDDQ_KLM
  BA(0)  = M_M_BA<0>
  A16_RAS_N  = M_M_MA<16>
  VDD(17)  = PVDDQ_KLM
  S0_N  = M_M_CS_N<0>
  VDD(16)  = PVDDQ_KLM
  A15_CAS_N  = M_M_MA<15>
  ODT(0)  = M_M_ODT<0>
  VDD(15)  = PVDDQ_KLM
  S1_N  = M_M_CS_N<1>
  VDD(14)  = PVDDQ_KLM
  ODT(1)  = M_M_ODT<1>
  VDD(13)  = PVDDQ_KLM
  S2_N_C(0)  = M_M_CS_N<2>
  VSS(67)  = GND
  DQ(36)  = M_M_DQ<37>
  VSS(66)  = GND
  DQ(32)  = M_M_DQ<33>
  VSS(65)  = GND
  DQS13P  = M_M_DQS_DP<13>
  DQS13N  = M_M_DQS_DN<13>
  VSS(64)  = GND
  DQ(38)  = M_M_DQ<39>
  VSS(63)  = GND
  DQ(34)  = M_M_DQ<35>
  VSS(62)  = GND
  DQ(44)  = M_M_DQ<45>
  VSS(61)  = GND
  DQ(40)  = M_M_DQ<41>
  VSS(60)  = GND
  DQS14P  = M_M_DQS_DP<14>
  DQS14N  = M_M_DQS_DN<14>
  VSS(59)  = GND
  DQ(46)  = M_M_DQ<47>
  VSS(58)  = GND
  DQ(42)  = M_M_DQ<43>
  VSS(57)  = GND
  DQ(52)  = M_M_DQ<53>
  VSS(56)  = GND
  DQ(48)  = M_M_DQ<49>
  VSS(55)  = GND
  DQS15P  = M_M_DQS_DP<15>
  DQS15N  = M_M_DQS_DN<15>
  VSS(54)  = GND
  DQ(54)  = M_M_DQ<55>
  VSS(53)  = GND
  DQ(50)  = M_M_DQ<51>
  VSS(52)  = GND
  DQ(60)  = M_M_DQ<61>
  VSS(51)  = GND
  DQ(56)  = M_M_DQ<57>
  VSS(50)  = GND
  DQS16P  = M_M_DQS_DP<16>
  DQS16N  = M_M_DQS_DN<16>
  VSS(49)  = GND
  DQ(62)  = M_M_DQ<63>
  VSS(48)  = GND
  DQ(58)  = M_M_DQ<59>
  VSS(47)  = GND
  SA(0)  = GND
  SA(1)  = GND
  SCL  = SMB_DDR_KLM_VPP_SCL
  VPP(4)  = PVPP_KLM
  VPP(3)  = PVPP_KLM
  RFU(2)  = TP_CH_M_DIMM_M0_RFU_2
  \12v\(0)  = P12V_NVDIMM_KLM
  VREFCA  = M_M_VREF
  VSS(46)  = GND
  DQ(5)  = M_M_DQ<4>
  VSS(45)  = GND
  DQ(1)  = M_M_DQ<0>
  VSS(44)  = GND
  DQS0N  = M_M_DQS_DN<0>
  DQS0P  = M_M_DQS_DP<0>
  VSS(43)  = GND
  DQ(7)  = M_M_DQ<6>
  VSS(42)  = GND
  DQ(3)  = M_M_DQ<2>
  VSS(41)  = GND
  DQ(13)  = M_M_DQ<12>
  VSS(40)  = GND
  DQ(9)  = M_M_DQ<8>
  VSS(39)  = GND
  DQS1N  = M_M_DQS_DN<1>
  DQS1P  = M_M_DQS_DP<1>
  VSS(38)  = GND
  DQ(15)  = M_M_DQ<14>
  VSS(37)  = GND
  DQ(11)  = M_M_DQ<10>
  VSS(36)  = GND
  DQ(21)  = M_M_DQ<20>
  VSS(35)  = GND
  DQ(17)  = M_M_DQ<16>
  VSS(34)  = GND
  DQS2N  = M_M_DQS_DN<2>
  DQS2P  = M_M_DQS_DP<2>
  VSS(33)  = GND
  DQ(23)  = M_M_DQ<22>
  VSS(32)  = GND
  DQ(19)  = M_M_DQ<18>
  VSS(31)  = GND
  DQ(29)  = M_M_DQ<28>
  VSS(30)  = GND
  DQ(25)  = M_M_DQ<24>
  VSS(29)  = GND
  DQS3N  = M_M_DQS_DN<3>
  DQS3P  = M_M_DQS_DP<3>
  VSS(28)  = GND
  DQ(31)  = M_M_DQ<30>
  VSS(27)  = GND
  DQ(27)  = M_M_DQ<26>
  VSS(26)  = GND
  CB(5)  = M_M_ECC<4>
  VSS(25)  = GND
  CB(1)  = M_M_ECC<0>
  VSS(24)  = GND
  DQS8N  = M_M_DQS_DN<8>
  DQS8P  = M_M_DQS_DP<8>
  VSS(23)  = GND
  CB(7)  = M_M_ECC<6>
  VSS(22)  = GND
  CB(3)  = M_M_ECC<2>
  VSS(21)  = GND
  CKE(1)  = M_M_CKE<1>
  VDD(12)  = PVDDQ_KLM
  RFU(0)  = TP_CH_M_DIMM_M0_RFU_0
  VDD(11)  = PVDDQ_KLM
  BG(1)  = M_M_BG<1>
  ALERT_N  = M_M_ALERT_N
  VDD(10)  = PVDDQ_KLM
  A11  = M_M_MA<11>
  A7  = M_M_MA<7>
  VDD(9)  = PVDDQ_KLM
  A5  = M_M_MA<5>
  A4  = M_M_MA<4>
  VDD(8)  = PVDDQ_KLM
  A2  = M_M_MA<2>
  VDD(7)  = PVDDQ_KLM
  CK1P  = M_M_CLK_DP<1>
  CK1N  = M_M_CLK_DN<1>
  VDD(6)  = PVDDQ_KLM
  VTT(0)  = PVTT_KLM
  PAR  = M_M_PAR
  VDD(5)  = PVDDQ_KLM
  BA(1)  = M_M_BA<1>
  A10  = M_M_MA<10>
  VDD(4)  = PVDDQ_KLM
  RFU(1)  = TP_CH_M_DIMM_M0_RFU_1
  A14_WE_N  = M_M_MA<14>
  VDD(3)  = PVDDQ_KLM
  SAVE_N_NC  = FM_ADR_COMPLETE_KLM_N
  VDD(2)  = PVDDQ_KLM
  A13  = M_M_MA<13>
  VDD(1)  = PVDDQ_KLM
  A17  = M_M_MA<17>
  C(2)  = M_M_C<2>
  VDD(0)  = PVDDQ_KLM
  S3_N_C(1)  = M_M_CS_N<3>
  SA(2)  = PVPP_KLM
  VSS(20)  = GND
  DQ(37)  = M_M_DQ<36>
  VSS(19)  = GND
  DQ(33)  = M_M_DQ<32>
  VSS(18)  = GND
  DQS4N  = M_M_DQS_DN<4>
  DQS4P  = M_M_DQS_DP<4>
  VSS(17)  = GND
  DQ(39)  = M_M_DQ<38>
  VSS(16)  = GND
  DQ(35)  = M_M_DQ<34>
  VSS(15)  = GND
  DQ(45)  = M_M_DQ<44>
  VSS(14)  = GND
  DQ(41)  = M_M_DQ<40>
  VSS(13)  = GND
  DQS5N  = M_M_DQS_DN<5>
  DQS5P  = M_M_DQS_DP<5>
  VSS(12)  = GND
  DQ(47)  = M_M_DQ<46>
  VSS(11)  = GND
  DQ(43)  = M_M_DQ<42>
  VSS(10)  = GND
  DQ(53)  = M_M_DQ<52>
  VSS(9)  = GND
  DQ(49)  = M_M_DQ<48>
  VSS(8)  = GND
  DQS6N  = M_M_DQS_DN<6>
  DQS6P  = M_M_DQS_DP<6>
  VSS(7)  = GND
  DQ(55)  = M_M_DQ<54>
  VSS(6)  = GND
  DQ(51)  = M_M_DQ<50>
  VSS(5)  = GND
  DQ(61)  = M_M_DQ<60>
  VSS(4)  = GND
  DQ(57)  = M_M_DQ<56>
  VSS(3)  = GND
  DQS7N  = M_M_DQS_DN<7>
  DQS7P  = M_M_DQS_DP<7>
  VSS(2)  = GND
  DQ(63)  = M_M_DQ<62>
  VSS(1)  = GND
  DQ(59)  = M_M_DQ<58>
  VSS(0)  = GND
  VDDSPD  = PVPP_KLM
  SDA  = SMB_DDR_KLM_VPP_SDA
  VPP(1)  = PVPP_KLM
  VPP(0)  = PVPP_KLM
  VPP(2)  = PVPP_KLM

(kicad_pcb
	(version 20260206)
	(generator "pcbnew")
	(generator_version "10.0")
	(general
		(thickness 1.6)
		(legacy_teardrops no)
	)
	(paper "A4")
	(title_block
		(title "Wiwynn_Tioga_Pass_MB.brd")
		(comment 1 "Tioga Pass / footprint 830 of 4770 (J1A1), pads 1-51 of 291")
	)
	(layers
		(0 "F.Cu" signal "TOP")
		(4 "In1.Cu" signal "L2GND")
		(6 "In2.Cu" signal "L3")
		(8 "In3.Cu" signal "L4GND")
		(10 "In4.Cu" signal "L5")
		(12 "In5.Cu" signal "L6GND")
		(14 "In6.Cu" signal "L7VCC")
		(16 "In7.Cu" signal "L8VCC")
		(18 "In8.Cu" signal "L9GND")
		(20 "In9.Cu" signal "L10")
		(22 "In10.Cu" signal "L11GND")
		(24 "In11.Cu" signal "L12")
		(26 "In12.Cu" signal "L13GND")
		(2 "B.Cu" signal "BOTTOM")
		(9 "F.Adhes" user "F.Adhesive")
		(11 "B.Adhes" user "B.Adhesive")
		(13 "F.Paste" user "Package Geometry/Pastemask Top")
		(15 "B.Paste" user "Package Geometry/Pastemask Bottom")
		(5 "F.SilkS" user "Ref Des/Silkscreen Top")
		(7 "B.SilkS" user "Ref Des/Silkscreen Bottom")
		(1 "F.Mask" user "Board Geometry/Soldermask Top")
		(3 "B.Mask" user "Board Geometry/Soldermask Bottom")
		(17 "Dwgs.User" user "User.Drawings")
		(19 "Cmts.User" user "User.Comments")
		(21 "Eco1.User" user "User.Eco1")
		(23 "Eco2.User" user "User.Eco2")
		(25 "Edge.Cuts" user "Board Geometry/Outline")
		(27 "Margin" user)
		(31 "F.CrtYd" user "Package Geometry/Place Bound Top")
		(29 "B.CrtYd" user "Package Geometry/Place Bound Bottom")
		(35 "F.Fab" user "Ref Des/Assembly Top")
		(33 "B.Fab" user "Ref Des/Assembly Bottom")
	)
	(footprint ""
		(layer "F.Cu")
		(at 29.699458 -152.273 90)
		(property "Reference" "J1A1"
			(at -2.572512 42.563542 0)
			(unlocked yes)
			(layer "F.SilkS")
			(effects
				(font
					(size 0.7874 0.5842)
					(thickness 0.1524)
				)
				(justify left)
			)
		)
		(property "Value" ""
			(at 0 0 90)
			(layer "F.Fab")
			(effects
				(font
					(size 1.27 1.27)
				)
			)
		)
		(duplicate_pad_numbers_are_jumpers no)
		(pad "" thru_hole circle
			(at 2.29997 -5.649976 90)
			(size 2.8194 2.8194)
			(drill 2.4384)
			(layers "*.Cu" "*.Mask")
			(remove_unused_layers no)
			(clearance 0.127)
			(thermal_gap 0.127)
		)
		(pad "" thru_hole oval
			(at 2.29997 68.90004 90)
			(size 2.8194 1.5748)
			(drill oval 2.4384 1.1938)
			(layers "*.Cu" "*.Mask")
			(remove_unused_layers no)
			(clearance 0.127)
			(thermal_gap 0.127)
		)
		(pad "" thru_hole circle
			(at 2.29997 132.299964 90)
			(size 2.8194 2.8194)
			(drill 2.4384)
			(layers "*.Cu" "*.Mask")
			(remove_unused_layers no)
			(clearance 0.127)
			(thermal_gap 0.127)
		)
		(pad "1" smd rect
			(at 0 0 90)
			(size 1.8034 0.508)
			(layers "F.Cu" "F.Mask" "F.Paste")
			(net "P12V_NVDIMM_KLM")
		)
		(pad "2" smd rect
			(at 0 0.849884 90)
			(size 1.8034 0.508)
			(layers "F.Cu" "F.Mask" "F.Paste")
			(net "GND")
		)
		(pad "3" smd rect
			(at 0 1.700022 90)
			(size 1.8034 0.508)
			(layers "F.Cu" "F.Mask" "F.Paste")
			(net "M_M_DQ<5>")
		)
		(pad "4" smd rect
			(at 0 2.549906 90)
			(size 1.8034 0.508)
			(layers "F.Cu" "F.Mask" "F.Paste")
			(net "GND")
		)
		(pad "5" smd rect
			(at 0 3.400044 90)
			(size 1.8034 0.508)
			(layers "F.Cu" "F.Mask" "F.Paste")
			(net "M_M_DQ<1>")
		)
		(pad "6" smd rect
			(at 0 4.249928 90)
			(size 1.8034 0.508)
			(layers "F.Cu" "F.Mask" "F.Paste")
			(net "GND")
		)
		(pad "7" smd rect
			(at 0 5.100066 90)
			(size 1.8034 0.508)
			(layers "F.Cu" "F.Mask" "F.Paste")
			(net "M_M_DQS_DP<9>")
		)
		(pad "8" smd rect
			(at 0 5.94995 90)
			(size 1.8034 0.508)
			(layers "F.Cu" "F.Mask" "F.Paste")
			(net "M_M_DQS_DN<9>")
		)
		(pad "9" smd rect
			(at 0 6.800088 90)
			(size 1.8034 0.508)
			(layers "F.Cu" "F.Mask" "F.Paste")
			(net "GND")
		)
		(pad "10" smd rect
			(at 0 7.649972 90)
			(size 1.8034 0.508)
			(layers "F.Cu" "F.Mask" "F.Paste")
			(net "M_M_DQ<7>")
		)
		(pad "11" smd rect
			(at 0 8.50011 90)
			(size 1.8034 0.508)
			(layers "F.Cu" "F.Mask" "F.Paste")
			(net "GND")
		)
		(pad "12" smd rect
			(at 0 9.349994 90)
			(size 1.8034 0.508)
			(layers "F.Cu" "F.Mask" "F.Paste")
			(net "M_M_DQ<3>")
		)
		(pad "13" smd rect
			(at 0 10.199878 90)
			(size 1.8034 0.508)
			(layers "F.Cu" "F.Mask" "F.Paste")
			(net "GND")
		)
		(pad "14" smd rect
			(at 0 11.050016 90)
			(size 1.8034 0.508)
			(layers "F.Cu" "F.Mask" "F.Paste")
			(net "M_M_DQ<13>")
		)
		(pad "15" smd rect
			(at 0 11.8999 90)
			(size 1.8034 0.508)
			(layers "F.Cu" "F.Mask" "F.Paste")
			(net "GND")
		)
		(pad "16" smd rect
			(at 0 12.750038 90)
			(size 1.8034 0.508)
			(layers "F.Cu" "F.Mask" "F.Paste")
			(net "M_M_DQ<9>")
		)
		(pad "17" smd rect
			(at 0 13.599922 90)
			(size 1.8034 0.508)
			(layers "F.Cu" "F.Mask" "F.Paste")
			(net "GND")
		)
		(pad "18" smd rect
			(at 0 14.45006 90)
			(size 1.8034 0.508)
			(layers "F.Cu" "F.Mask" "F.Paste")
			(net "M_M_DQS_DP<10>")
		)
		(pad "19" smd rect
			(at 0 15.299944 90)
			(size 1.8034 0.508)
			(layers "F.Cu" "F.Mask" "F.Paste")
			(net "M_M_DQS_DN<10>")
		)
		(pad "20" smd rect
			(at 0 16.150082 90)
			(size 1.8034 0.508)
			(layers "F.Cu" "F.Mask" "F.Paste")
			(net "GND")
		)
		(pad "21" smd rect
			(at 0 16.999966 90)
			(size 1.8034 0.508)
			(layers "F.Cu" "F.Mask" "F.Paste")
			(net "M_M_DQ<15>")
		)
		(pad "22" smd rect
			(at 0 17.850104 90)
			(size 1.8034 0.508)
			(layers "F.Cu" "F.Mask" "F.Paste")
			(net "GND")
		)
		(pad "23" smd rect
			(at 0 18.699988 90)
			(size 1.8034 0.508)
			(layers "F.Cu" "F.Mask" "F.Paste")
			(net "M_M_DQ<11>")
		)
		(pad "24" smd rect
			(at 0 19.550126 90)
			(size 1.8034 0.508)
			(layers "F.Cu" "F.Mask" "F.Paste")
			(net "GND")
		)
		(pad "25" smd rect
			(at 0 20.40001 90)
			(size 1.8034 0.508)
			(layers "F.Cu" "F.Mask" "F.Paste")
			(net "M_M_DQ<21>")
		)
		(pad "26" smd rect
			(at 0 21.249894 90)
			(size 1.8034 0.508)
			(layers "F.Cu" "F.Mask" "F.Paste")
			(net "GND")
		)
		(pad "27" smd rect
			(at 0 22.100032 90)
			(size 1.8034 0.508)
			(layers "F.Cu" "F.Mask" "F.Paste")
			(net "M_M_DQ<17>")
		)
		(pad "28" smd rect
			(at 0 22.949916 90)
			(size 1.8034 0.508)
			(layers "F.Cu" "F.Mask" "F.Paste")
			(net "GND")
		)
		(pad "29" smd rect
			(at 0 23.800054 90)
			(size 1.8034 0.508)
			(layers "F.Cu" "F.Mask" "F.Paste")
			(net "M_M_DQS_DP<11>")
		)
		(pad "30" smd rect
			(at 0 24.649938 90)
			(size 1.8034 0.508)
			(layers "F.Cu" "F.Mask" "F.Paste")
			(net "M_M_DQS_DN<11>")
		)
		(pad "31" smd rect
			(at 0 25.500076 90)
			(size 1.8034 0.508)
			(layers "F.Cu" "F.Mask" "F.Paste")
			(net "GND")
		)
		(pad "32" smd rect
			(at 0 26.34996 90)
			(size 1.8034 0.508)
			(layers "F.Cu" "F.Mask" "F.Paste")
			(net "M_M_DQ<23>")
		)
		(pad "33" smd rect
			(at 0 27.200098 90)
			(size 1.8034 0.508)
			(layers "F.Cu" "F.Mask" "F.Paste")
			(net "GND")
		)
		(pad "34" smd rect
			(at 0 28.049982 90)
			(size 1.8034 0.508)
			(layers "F.Cu" "F.Mask" "F.Paste")
			(net "M_M_DQ<19>")
		)
		(pad "35" smd rect
			(at 0 28.90012 90)
			(size 1.8034 0.508)
			(layers "F.Cu" "F.Mask" "F.Paste")
			(net "GND")
		)
		(pad "36" smd rect
			(at 0 29.750004 90)
			(size 1.8034 0.508)
			(layers "F.Cu" "F.Mask" "F.Paste")
			(net "M_M_DQ<29>")
		)
		(pad "37" smd rect
			(at 0 30.599888 90)
			(size 1.8034 0.508)
			(layers "F.Cu" "F.Mask" "F.Paste")
			(net "GND")
		)
		(pad "38" smd rect
			(at 0 31.450026 90)
			(size 1.8034 0.508)
			(layers "F.Cu" "F.Mask" "F.Paste")
			(net "M_M_DQ<25>")
		)
		(pad "39" smd rect
			(at 0 32.29991 90)
			(size 1.8034 0.508)
			(layers "F.Cu" "F.Mask" "F.Paste")
			(net "GND")
		)
		(pad "40" smd rect
			(at 0 33.150048 90)
			(size 1.8034 0.508)
			(layers "F.Cu" "F.Mask" "F.Paste")
			(net "M_M_DQS_DP<12>")
		)
		(pad "41" smd rect
			(at 0 33.999932 90)
			(size 1.8034 0.508)
			(layers "F.Cu" "F.Mask" "F.Paste")
			(net "M_M_DQS_DN<12>")
		)
		(pad "42" smd rect
			(at 0 34.85007 90)
			(size 1.8034 0.508)
			(layers "F.Cu" "F.Mask" "F.Paste")
			(net "GND")
		)
		(pad "43" smd rect
			(at 0 35.699954 90)
			(size 1.8034 0.508)
			(layers "F.Cu" "F.Mask" "F.Paste")
			(net "M_M_DQ<31>")
		)
		(pad "44" smd rect
			(at 0 36.550092 90)
			(size 1.8034 0.508)
			(layers "F.Cu" "F.Mask" "F.Paste")
			(net "GND")
		)
		(pad "45" smd rect
			(at 0 37.399976 90)
			(size 1.8034 0.508)
			(layers "F.Cu" "F.Mask" "F.Paste")
			(net "M_M_DQ<27>")
		)
		(pad "46" smd rect
			(at 0 38.250114 90)
			(size 1.8034 0.508)
			(layers "F.Cu" "F.Mask" "F.Paste")
			(net "GND")
		)
		(pad "47" smd rect
			(at 0 39.099998 90)
			(size 1.8034 0.508)
			(layers "F.Cu" "F.Mask" "F.Paste")
			(net "M_M_ECC<5>")
		)
		(pad "48" smd rect
			(at 0 39.949882 90)
			(size 1.8034 0.508)
			(layers "F.Cu" "F.Mask" "F.Paste")
			(net "GND")
		)
	)
)
